(kicad_pcb
	(version 20260206)
	(generator "pcbnew")
	(generator_version "10.0")
	(general
		(thickness 1.6)
		(legacy_teardrops no)
	)
	(paper "A4")
	(title_block
		(title "dpb — 14545-sa.0730WZS0815.brd")
		(comment 1 "Honey Badger (Wiwynn) / footprints 190-194 of 1066")
	)
	(layers
		(0 "F.Cu" signal "TOP")
		(4 "In1.Cu" signal "L2GND")
		(6 "In2.Cu" signal "L3")
		(8 "In3.Cu" signal "L4VCC")
		(10 "In4.Cu" signal "L5VCC")
		(12 "In5.Cu" signal "L6")
		(14 "In6.Cu" signal "L7GND")
		(2 "B.Cu" signal "BOTTOM")
		(9 "F.Adhes" user "F.Adhesive")
		(11 "B.Adhes" user "B.Adhesive")
		(13 "F.Paste" user "Package Geometry/Pastemask Top")
		(15 "B.Paste" user "Package Geometry/Pastemask Bottom")
		(5 "F.SilkS" user "Ref Des/Silkscreen Top")
		(7 "B.SilkS" user "Ref Des/Silkscreen Bottom")
		(1 "F.Mask" user "Board Geometry/Soldermask Top")
		(3 "B.Mask" user "Board Geometry/Soldermask Bottom")
		(17 "Dwgs.User" user "User.Drawings")
		(19 "Cmts.User" user "User.Comments")
		(21 "Eco1.User" user "User.Eco1")
		(23 "Eco2.User" user "User.Eco2")
		(25 "Edge.Cuts" user "Board Geometry/Outline")
		(27 "Margin" user)
		(31 "F.CrtYd" user "Package Geometry/Place Bound Top")
		(29 "B.CrtYd" user "Package Geometry/Place Bound Bottom")
		(35 "F.Fab" user "Ref Des/Assembly Top")
		(33 "B.Fab" user "Ref Des/Assembly Bottom")
	)
	(footprint ""
		(layer "F.Cu")
		(at 6.248146 -268.2367 -90)
		(property "Reference" "Q46"
			(at 0 0 270)
			(layer "F.SilkS")
			(hide yes)
			(effects
				(font
					(size 1.27 1.27)
				)
			)
		)
		(property "Value" "PMBS3904-1-GP"
			(at 0 -9.0932 270)
			(unlocked yes)
			(layer "F.Fab")
			(hide yes)
			(effects
				(font
					(size 1.016 1.016)
					(thickness 0.1524)
				)
			)
		)
		(property "Device Type" "SOT-23-10H44"
			(at 0 -10.6172 270)
			(unlocked yes)
			(layer "F.Fab")
			(hide yes)
			(effects
				(font
					(size 1.016 1.016)
					(thickness 0.1524)
				)
			)
		)
		(duplicate_pad_numbers_are_jumpers no)
		(fp_line
			(start -1.279144 2.15265)
			(end -0.701294 2.15265)
			(stroke
				(width 0.0127)
				(type default)
			)
			(layer "F.SilkS")
		)
		(fp_line
			(start -0.71628 2.15265)
			(end -1.26492 2.15265)
			(stroke
				(width 0.0127)
				(type default)
			)
			(layer "F.SilkS")
		)
		(fp_line
			(start -1.279398 2.152142)
			(end -0.9906 1.86309)
			(stroke
				(width 0.0127)
				(type default)
			)
			(layer "F.SilkS")
		)
		(fp_line
			(start -0.719074 2.145538)
			(end -1.265936 2.14122)
			(stroke
				(width 0.0127)
				(type default)
			)
			(layer "F.SilkS")
		)
		(fp_line
			(start -1.260856 2.1336)
			(end -0.720344 2.1336)
			(stroke
				(width 0.0127)
				(type default)
			)
			(layer "F.SilkS")
		)
		(fp_line
			(start -1.251458 2.124202)
			(end -0.729996 2.124202)
			(stroke
				(width 0.0127)
				(type default)
			)
			(layer "F.SilkS")
		)
		(fp_line
			(start -1.241806 2.11455)
			(end -0.739394 2.11455)
			(stroke
				(width 0.0127)
				(type default)
			)
			(layer "F.SilkS")
		)
		(fp_line
			(start -1.232408 2.105152)
			(end -0.749046 2.105152)
			(stroke
				(width 0.0127)
				(type default)
			)
			(layer "F.SilkS")
		)
		(fp_line
			(start -1.222756 2.0955)
			(end -0.758444 2.0955)
			(stroke
				(width 0.0127)
				(type default)
			)
			(layer "F.SilkS")
		)
		(fp_line
			(start -1.213358 2.086102)
			(end -0.768096 2.086102)
			(stroke
				(width 0.0127)
				(type default)
			)
			(layer "F.SilkS")
		)
		(fp_line
			(start -1.203706 2.07645)
			(end -0.777494 2.07645)
			(stroke
				(width 0.0127)
				(type default)
			)
			(layer "F.SilkS")
		)
		(fp_line
			(start -1.194308 2.067052)
			(end -0.787146 2.067052)
			(stroke
				(width 0.0127)
				(type default)
			)
			(layer "F.SilkS")
		)
		(fp_line
			(start -1.184656 2.0574)
			(end -0.796544 2.0574)
			(stroke
				(width 0.0127)
				(type default)
			)
			(layer "F.SilkS")
		)
		(fp_line
			(start -1.175258 2.048002)
			(end -0.806196 2.048002)
			(stroke
				(width 0.0127)
				(type default)
			)
			(layer "F.SilkS")
		)
		(fp_line
			(start -1.165606 2.03835)
			(end -0.815594 2.03835)
			(stroke
				(width 0.0127)
				(type default)
			)
			(layer "F.SilkS")
		)
		(fp_line
			(start -1.156208 2.028952)
			(end -0.825246 2.028952)
			(stroke
				(width 0.0127)
				(type default)
			)
			(layer "F.SilkS")
		)
		(fp_line
			(start -1.146556 2.0193)
			(end -0.834644 2.0193)
			(stroke
				(width 0.0127)
				(type default)
			)
			(layer "F.SilkS")
		)
		(fp_line
			(start -1.137158 2.009902)
			(end -0.844296 2.009902)
			(stroke
				(width 0.0127)
				(type default)
			)
			(layer "F.SilkS")
		)
		(fp_line
			(start -1.127506 2.00025)
			(end -0.853694 2.00025)
			(stroke
				(width 0.0127)
				(type default)
			)
			(layer "F.SilkS")
		)
		(fp_line
			(start -1.118108 1.990852)
			(end -0.863346 1.990852)
			(stroke
				(width 0.0127)
				(type default)
			)
			(layer "F.SilkS")
		)
		(fp_line
			(start -1.108456 1.9812)
			(end -0.872744 1.9812)
			(stroke
				(width 0.0127)
				(type default)
			)
			(layer "F.SilkS")
		)
		(fp_line
			(start -1.099058 1.971802)
			(end -0.882396 1.971802)
			(stroke
				(width 0.0127)
				(type default)
			)
			(layer "F.SilkS")
		)
		(fp_line
			(start -1.089406 1.96215)
			(end -0.891794 1.96215)
			(stroke
				(width 0.0127)
				(type default)
			)
			(layer "F.SilkS")
		)
		(fp_line
			(start -1.080008 1.952752)
			(end -0.901446 1.952752)
			(stroke
				(width 0.0127)
				(type default)
			)
			(layer "F.SilkS")
		)
		(fp_line
			(start -1.070356 1.9431)
			(end -0.910844 1.9431)
			(stroke
				(width 0.0127)
				(type default)
			)
			(layer "F.SilkS")
		)
		(fp_line
			(start -1.060958 1.933702)
			(end -0.920496 1.933702)
			(stroke
				(width 0.0127)
				(type default)
			)
			(layer "F.SilkS")
		)
		(fp_line
			(start -1.051306 1.92405)
			(end -0.929894 1.92405)
			(stroke
				(width 0.0127)
				(type default)
			)
			(layer "F.SilkS")
		)
		(fp_line
			(start -1.041908 1.914652)
			(end -0.939546 1.914652)
			(stroke
				(width 0.0127)
				(type default)
			)
			(layer "F.SilkS")
		)
		(fp_line
			(start -1.032256 1.905)
			(end -0.948944 1.905)
			(stroke
				(width 0.0127)
				(type default)
			)
			(layer "F.SilkS")
		)
		(fp_line
			(start -1.022858 1.895602)
			(end -0.958596 1.895602)
			(stroke
				(width 0.0127)
				(type default)
			)
			(layer "F.SilkS")
		)
		(fp_line
			(start -1.013206 1.88595)
			(end -0.967994 1.88595)
			(stroke
				(width 0.0127)
				(type default)
			)
			(layer "F.SilkS")
		)
		(fp_line
			(start -1.7526 1.8796)
			(end -1.7526 0.9906)
			(stroke
				(width 0.3302)
				(type default)
			)
			(layer "F.SilkS")
		)
		(fp_line
			(start -0.635 1.8796)
			(end -1.7526 1.8796)
			(stroke
				(width 0.3302)
				(type default)
			)
			(layer "F.SilkS")
		)
		(fp_line
			(start -1.003808 1.876552)
			(end -0.977646 1.876552)
			(stroke
				(width 0.0127)
				(type default)
			)
			(layer "F.SilkS")
		)
		(fp_line
			(start -0.994156 1.8669)
			(end -0.987044 1.8669)
			(stroke
				(width 0.0127)
				(type default)
			)
			(layer "F.SilkS")
		)
		(fp_line
			(start -0.9906 1.86309)
			(end -0.701294 2.15265)
			(stroke
				(width 0.0127)
				(type default)
			)
			(layer "F.SilkS")
		)
		(fp_line
			(start -1.651 1.778)
			(end 1.651 1.778)
			(stroke
				(width 0.1524)
				(type default)
			)
			(layer "F.SilkS")
		)
		(fp_line
			(start 1.651 1.778)
			(end 1.651 -1.778)
			(stroke
				(width 0.1524)
				(type default)
			)
			(layer "F.SilkS")
		)
		(fp_line
			(start -1.651 -1.778)
			(end -1.651 1.778)
			(stroke
				(width 0.1524)
				(type default)
			)
			(layer "F.SilkS")
		)
		(fp_line
			(start 1.651 -1.778)
			(end -1.651 -1.778)
			(stroke
				(width 0.1524)
				(type default)
			)
			(layer "F.SilkS")
		)
		(fp_poly
			(pts
				(xy -1.285748 2.159) (xy -1.285748 1.8796) (xy -1.778 1.8796) (xy -1.778 -1.8796) (xy 1.778 -1.8796)
				(xy 1.778 1.8796) (xy -0.694944 1.8796) (xy -0.694944 2.159)
			)
			(stroke
				(width 0)
				(type default)
			)
			(fill no)
			(layer "F.CrtYd")
		)
		(fp_poly
			(pts
				(xy -1.285748 2.159) (xy -1.285748 1.8796) (xy -1.778 1.8796) (xy -1.778 -1.8796) (xy 1.778 -1.8796)
				(xy 1.778 1.8796) (xy -0.694944 1.8796) (xy -0.694944 2.159)
			)
			(stroke
				(width 0)
				(type default)
			)
			(fill no)
			(layer "F.Fab")
		)
		(pad "1" smd rect
			(at -0.98425 0.9525 270)
			(size 0.762 1.143)
			(layers "F.Cu" "F.Mask" "F.Paste")
			(net "FLT_HDD12_B")
		)
		(pad "2" smd rect
			(at 0.98425 0.9525 270)
			(size 0.762 1.143)
			(layers "F.Cu" "F.Mask" "F.Paste")
			(net "GND")
		)
		(pad "3" smd rect
			(at 0 -0.9525 270)
			(size 0.762 1.143)
			(layers "F.Cu" "F.Mask" "F.Paste")
			(net "DRIVE_ACT_12")
		)
	)
	(footprint ""
		(layer "F.Cu")
		(at 193.167 -396.494 90)
		(property "Reference" "R479"
			(at 0 0 90)
			(layer "F.SilkS")
			(hide yes)
			(effects
				(font
					(size 1.27 1.27)
				)
			)
		)
		(property "Value" "200KR2F-L-GP"
			(at 0.064008 -3.993896 90)
			(unlocked yes)
			(layer "F.Fab")
			(hide yes)
			(effects
				(font
					(size 1.016 1.016)
					(thickness 0.1524)
				)
			)
		)
		(property "Device Type" "R402H16"
			(at 0.064008 -5.517896 90)
			(unlocked yes)
			(layer "F.Fab")
			(hide yes)
			(effects
				(font
					(size 1.016 1.016)
					(thickness 0.1524)
				)
			)
		)
		(duplicate_pad_numbers_are_jumpers no)
		(fp_line
			(start 0.508 -0.9398)
			(end -0.508 -0.9398)
			(stroke
				(width 0.1524)
				(type default)
			)
			(layer "F.SilkS")
		)
		(fp_line
			(start -0.508 -0.9398)
			(end -0.508 0.9398)
			(stroke
				(width 0.1524)
				(type default)
			)
			(layer "F.SilkS")
		)
		(fp_rect
			(start -0.508 0.9398)
			(end 0.508 -0.9398)
			(stroke
				(width 0)
				(type default)
			)
			(fill no)
			(layer "F.CrtYd")
		)
		(fp_rect
			(start -0.508 0.9398)
			(end 0.508 -0.9398)
			(stroke
				(width 0)
				(type default)
			)
			(fill no)
			(layer "F.Fab")
		)
		(pad "1" smd custom
			(at 0 -0.4445 90)
			(size 0.1397 0.1397)
			(layers "F.Cu" "F.Mask" "F.Paste")
			(net "SW_HDD1_R")
			(options
				(clearance outline)
				(anchor circle)
			)
			(primitives
				(gr_poly
					(pts
						(arc
							(start -0.1778 -0.2794)
							(mid -0.249642 -0.249642)
							(end -0.2794 -0.1778)
						)
						(arc
							(start -0.2794 0.1778)
							(mid -0.249642 0.249642)
							(end -0.1778 0.2794)
						)
						(arc
							(start 0.1778 0.2794)
							(mid 0.249642 0.249642)
							(end 0.2794 0.1778)
						)
						(arc
							(start 0.2794 -0.1778)
							(mid 0.249642 -0.249642)
							(end 0.1778 -0.2794)
						)
					)
					(width 0)
					(fill yes)
				)
			)
		)
		(pad "2" smd custom
			(at 0 0.4445 90)
			(size 0.1397 0.1397)
			(layers "F.Cu" "F.Mask" "F.Paste")
			(net "SW_HDD1_N")
			(options
				(clearance outline)
				(anchor circle)
			)
			(primitives
				(gr_poly
					(pts
						(arc
							(start -0.1778 -0.2794)
							(mid -0.249642 -0.249642)
							(end -0.2794 -0.1778)
						)
						(arc
							(start -0.2794 0.1778)
							(mid -0.249642 0.249642)
							(end -0.1778 0.2794)
						)
						(arc
							(start 0.1778 0.2794)
							(mid 0.249642 0.249642)
							(end 0.2794 0.1778)
						)
						(arc
							(start 0.2794 -0.1778)
							(mid 0.249642 -0.249642)
							(end 0.1778 -0.2794)
						)
					)
					(width 0)
					(fill yes)
				)
			)
		)
	)
	(footprint ""
		(layer "F.Cu")
		(at 84.200492 -84.610956 -90)
		(property "Reference" "R459"
			(at 0 0 270)
			(layer "F.SilkS")
			(hide yes)
			(effects
				(font
					(size 1.27 1.27)
				)
			)
		)
		(property "Value" "4K7R2J-2-GP"
			(at 0.064008 -3.993896 270)
			(unlocked yes)
			(layer "F.Fab")
			(hide yes)
			(effects
				(font
					(size 1.016 1.016)
					(thickness 0.1524)
				)
			)
		)
		(property "Device Type" "R402H16"
			(at 0.064008 -5.517896 270)
			(unlocked yes)
			(layer "F.Fab")
			(hide yes)
			(effects
				(font
					(size 1.016 1.016)
					(thickness 0.1524)
				)
			)
		)
		(duplicate_pad_numbers_are_jumpers no)
		(fp_line
			(start -0.508 -0.9398)
			(end -0.508 0.9398)
			(stroke
				(width 0.1524)
				(type default)
			)
			(layer "F.SilkS")
		)
		(fp_line
			(start 0.508 -0.9398)
			(end -0.508 -0.9398)
			(stroke
				(width 0.1524)
				(type default)
			)
			(layer "F.SilkS")
		)
		(fp_rect
			(start -0.508 0.9398)
			(end 0.508 -0.9398)
			(stroke
				(width 0)
				(type default)
			)
			(fill no)
			(layer "F.CrtYd")
		)
		(fp_rect
			(start -0.508 0.9398)
			(end 0.508 -0.9398)
			(stroke
				(width 0)
				(type default)
			)
			(fill no)
			(layer "F.Fab")
		)
		(pad "1" smd custom
			(at 0 -0.4445 270)
			(size 0.1397 0.1397)
			(layers "F.Cu" "F.Mask" "F.Paste")
			(net "P3V3")
			(options
				(clearance outline)
				(anchor circle)
			)
			(primitives
				(gr_poly
					(pts
						(arc
							(start -0.1778 -0.2794)
							(mid -0.249642 -0.249642)
							(end -0.2794 -0.1778)
						)
						(arc
							(start -0.2794 0.1778)
							(mid -0.249642 0.249642)
							(end -0.1778 0.2794)
						)
						(arc
							(start 0.1778 0.2794)
							(mid 0.249642 0.249642)
							(end 0.2794 0.1778)
						)
						(arc
							(start 0.2794 -0.1778)
							(mid 0.249642 -0.249642)
							(end 0.1778 -0.2794)
						)
					)
					(width 0)
					(fill yes)
				)
			)
		)
		(pad "2" smd custom
			(at 0 0.4445 270)
			(size 0.1397 0.1397)
			(layers "F.Cu" "F.Mask" "F.Paste")
			(net "SAS_EXP_B_PWR9")
			(options
				(clearance outline)
				(anchor circle)
			)
			(primitives
				(gr_poly
					(pts
						(arc
							(start -0.1778 -0.2794)
							(mid -0.249642 -0.249642)
							(end -0.2794 -0.1778)
						)
						(arc
							(start -0.2794 0.1778)
							(mid -0.249642 0.249642)
							(end -0.1778 0.2794)
						)
						(arc
							(start 0.1778 0.2794)
							(mid 0.249642 0.249642)
							(end 0.2794 0.1778)
						)
						(arc
							(start 0.2794 -0.1778)
							(mid 0.249642 -0.249642)
							(end 0.1778 -0.2794)
						)
					)
					(width 0)
					(fill yes)
				)
			)
		)
	)
	(footprint ""
		(layer "F.Cu")
		(at 33.019746 -57.9247 -90)
		(property "Reference" "C247"
			(at 0 0 270)
			(layer "F.SilkS")
			(hide yes)
			(effects
				(font
					(size 1.27 1.27)
				)
			)
		)
		(property "Value" "SCD01U50V2KX-1GP"
			(at 1.1811 -2.7051 270)
			(unlocked yes)
			(layer "F.Fab")
			(hide yes)
			(effects
				(font
					(size 1.016 1.016)
					(thickness 0.1524)
				)
			)
		)
		(property "Device Type" "C402H22"
			(at 1.1811 -4.2291 270)
			(unlocked yes)
			(layer "F.Fab")
			(hide yes)
			(effects
				(font
					(size 1.016 1.016)
					(thickness 0.1524)
				)
			)
		)
		(duplicate_pad_numbers_are_jumpers no)
		(fp_rect
			(start -0.4318 0.9525)
			(end 0.4318 -0.9525)
			(stroke
				(width 0)
				(type default)
			)
			(fill no)
			(layer "F.CrtYd")
		)
		(fp_rect
			(start -0.4318 0.9525)
			(end 0.4318 -0.9525)
			(stroke
				(width 0)
				(type default)
			)
			(fill no)
			(layer "F.Fab")
		)
		(pad "1" smd custom
			(at 0 -0.4445 270)
			(size 0.1524 0.1524)
			(layers "F.Cu" "F.Mask" "F.Paste")
			(net "SAS2X28_DRIVE_RX_P_A9")
			(options
				(clearance outline)
				(anchor circle)
			)
			(primitives
				(gr_poly
					(pts
						(arc
							(start 0.3048 -0.2032)
							(mid 0.275042 -0.275042)
							(end 0.2032 -0.3048)
						)
						(arc
							(start -0.2032 -0.3048)
							(mid -0.275042 -0.275042)
							(end -0.3048 -0.2032)
						)
						(arc
							(start -0.3048 0.2032)
							(mid -0.275042 0.275042)
							(end -0.2032 0.3048)
						)
						(arc
							(start 0.2032 0.3048)
							(mid 0.275042 0.275042)
							(end 0.3048 0.2032)
						)
					)
					(width 0)
					(fill yes)
				)
			)
		)
		(pad "2" smd custom
			(at 0 0.4445 270)
			(size 0.1524 0.1524)
			(layers "F.Cu" "F.Mask" "F.Paste")
			(net "SAS2X28_A_HDD9_RX_+")
			(options
				(clearance outline)
				(anchor circle)
			)
			(primitives
				(gr_poly
					(pts
						(arc
							(start 0.3048 -0.2032)
							(mid 0.275042 -0.275042)
							(end 0.2032 -0.3048)
						)
						(arc
							(start -0.2032 -0.3048)
							(mid -0.275042 -0.275042)
							(end -0.3048 -0.2032)
						)
						(arc
							(start -0.3048 0.2032)
							(mid -0.275042 0.275042)
							(end -0.2032 0.3048)
						)
						(arc
							(start 0.2032 0.3048)
							(mid 0.275042 0.275042)
							(end 0.3048 0.2032)
						)
					)
					(width 0)
					(fill yes)
				)
			)
		)
	)
	(footprint ""
		(layer "F.Cu")
		(at 57.912 -175.133 90)
		(property "Reference" "R393"
			(at 0 0 90)
			(layer "F.SilkS")
			(hide yes)
			(effects
				(font
					(size 1.27 1.27)
				)
			)
		)
		(property "Value" "0R2J-2-GP"
			(at 0.064008 -3.993896 90)
			(unlocked yes)
			(layer "F.Fab")
			(hide yes)
			(effects
				(font
					(size 1.016 1.016)
					(thickness 0.1524)
				)
			)
		)
		(property "Device Type" "R402H16"
			(at 0.064008 -5.517896 90)
			(unlocked yes)
			(layer "F.Fab")
			(hide yes)
			(effects
				(font
					(size 1.016 1.016)
					(thickness 0.1524)
				)
			)
		)
		(duplicate_pad_numbers_are_jumpers no)
		(fp_line
			(start 0.508 -0.9398)
			(end -0.508 -0.9398)
			(stroke
				(width 0.1524)
				(type default)
			)
			(layer "F.SilkS")
		)
		(fp_line
			(start -0.508 -0.9398)
			(end -0.508 0.9398)
			(stroke
				(width 0.1524)
				(type default)
			)
			(layer "F.SilkS")
		)
		(fp_rect
			(start -0.508 0.9398)
			(end 0.508 -0.9398)
			(stroke
				(width 0)
				(type default)
			)
			(fill no)
			(layer "F.CrtYd")
		)
		(fp_rect
			(start -0.508 0.9398)
			(end 0.508 -0.9398)
			(stroke
				(width 0)
				(type default)
			)
			(fill no)
			(layer "F.Fab")
		)
		(pad "1" smd custom
			(at 0 -0.4445 90)
			(size 0.1397 0.1397)
			(layers "F.Cu" "F.Mask" "F.Paste")
			(net "HDD_PRSNT_NET8")
			(options
				(clearance outline)
				(anchor circle)
			)
			(primitives
				(gr_poly
					(pts
						(arc
							(start -0.1778 -0.2794)
							(mid -0.249642 -0.249642)
							(end -0.2794 -0.1778)
						)
						(arc
							(start -0.2794 0.1778)
							(mid -0.249642 0.249642)
							(end -0.1778 0.2794)
						)
						(arc
							(start 0.1778 0.2794)
							(mid 0.249642 0.249642)
							(end 0.2794 0.1778)
						)
						(arc
							(start 0.2794 -0.1778)
							(mid 0.249642 -0.249642)
							(end 0.1778 -0.2794)
						)
					)
					(width 0)
					(fill yes)
				)
			)
		)
		(pad "2" smd custom
			(at 0 0.4445 90)
			(size 0.1397 0.1397)
			(layers "F.Cu" "F.Mask" "F.Paste")
			(net "HDD8_LED_B")
			(options
				(clearance outline)
				(anchor circle)
			)
			(primitives
				(gr_poly
					(pts
						(arc
							(start -0.1778 -0.2794)
							(mid -0.249642 -0.249642)
							(end -0.2794 -0.1778)
						)
						(arc
							(start -0.2794 0.1778)
							(mid -0.249642 0.249642)
							(end -0.1778 0.2794)
						)
						(arc
							(start 0.1778 0.2794)
							(mid 0.249642 0.249642)
							(end 0.2794 0.1778)
						)
						(arc
							(start 0.2794 -0.1778)
							(mid 0.249642 -0.249642)
							(end 0.1778 -0.2794)
						)
					)
					(width 0)
					(fill yes)
				)
			)
		)
	)
)
